# T6G (Grand Teton) — schematic parts with pin connectivity, parts 6233–6376 of 8303; source: Cadence DE-HDL packaged netlist (pstxprt.dat, pstxnet.dat, pstchip.dat)

R1509  Q_RES  0 5% CHIP  pkg 0402LF  page 136 : 1 = HP_LVC3_OCP_V3_1_P12V_PWRGD ; 2 = HP_LVC3_OCP_V3_1_P12V_R2_PWRGD
R1510  Q_RES  4.7K 5% EMPTY  pkg 0201LF  page 353 : 1 = P1V8_CPU1_RT_1D ; 2 = JTAG_TDI_RT_CPU1_P3
R1511  Q_RES  4.7K 5% EMPTY  pkg 0201LF  page 353 : 1 = P1V8_CPU1_RT_1D ; 2 = JTAG_TMS_RT_CPU1_P3
R1512  Q_RES  1K 1% EMPTY  pkg 0201LF  page 353 : 1 = P1V8_CPU1_RT_1D ; 2 = JTAG_TDO_RT_CPU1_P3
R1513  Q_RES  4.7K 5% EMPTY  pkg 0201LF  page 353 : 1 = P1V8_CPU1_RT_1D ; 2 = JTAG_TCK_RT_CPU1_P3
R1514  Q_RES  0 5% CHIP  pkg 0201LF  page 184 : 1 = SMB_MUX_RT_R1_SCL ; 2 = SMB_MUX_RT_R2_SCL
R1515  Q_RES  0 5% CHIP  pkg 0201LF  page 184 : 1 = SMB_MUX_RT_R1_SDA ; 2 = SMB_MUX_RT_R2_SDA
R1516  Q_RES  33.2 1% CHIP  pkg 0402LF  page 151 : 1 = SMB_HOST_CLK_3V3AUX_SCL ; 2 = SMB_HOST_CLK_3V3AUX_SCL_R1
R1517  Q_RES  33.2 1% CHIP  pkg 0402LF  page 151 : 1 = SMB_HOST_CLK_3V3AUX_SDA ; 2 = SMB_HOST_CLK_3V3AUX_SDA_R1
R1518  Q_RES  0 5% CHIP  pkg 0402LF  page 136 : 1 = HP_LVC3_OCP_V3_1_PWRGD_R2 ; 2 = OCP_V3_1_P3V3_R3_PWRGD
R1519  Q_RES  0 5% EMPTY  pkg 0402LF  page 136 : 1 = OCP_V3_1_P3V3_R3_PWRGD ; 2 = OCP_V3_1_P3V3_PWRGD
R1520  Q_RES  0 5% CHIP  pkg 0402LF  page 140 : 1 = P12V_OCP_V3_2_BUF_EN_R ; 2 = P3V3_OCP_EN_2_R
R1521  Q_RES  0 5% CHIP  pkg 0402LF  page 141 : 1 = P12V_OCP_V3_2_BUF_EN_R ; 2 = P3V3_OCP_EN_2
R1522  Q_RES  0 5% CHIP  pkg 0402LF  page 247 : 1 = HP_LVC3_OCP_V3_2_R_EN ; 2 = P12V_OCP_V3_2_BUF_EN_R
R1523  Q_RES  0 5% CHIP  pkg 0402LF  page 142 : 1 = HP_LVC3_OCP_V3_2_P12V_PWRGD ; 2 = HP_LVC3_OCP_V3_2_P12V_PWRGD_R2
R1524  Q_RES  0 5% CHIP  pkg 0402LF  page 142 : 1 = HP_LVC3_OCP_V3_2_PWRGD_R2 ; 2 = OCP_V3_2_P3V3_R3_PWRGD
R1525  Q_RES  0 5% EMPTY  pkg 0402LF  page 142 : 1 = OCP_V3_2_P3V3_PWRGD ; 2 = OCP_V3_2_P3V3_R3_PWRGD
R1526  Q_RES  0 5% CHIP  pkg 0402LF  page 240 : 1 = PDB_PRSNT_N ; 2 = PDB_PRSNT_R_N
R1527  Q_RES  1K 1% CHIP  pkg 0402LF  page 83 : 1 = PRSNT_HDT_N ; 2 = P3V3_AUX
R1528  Q_RES  33 5% CHIP  pkg 0402LF  page 172 : 1 = PRSNT_HDT_N ; 2 = PRSNT_HDT_R_N
R1529  Q_RES  1K 1% EMPTY  pkg 0402LF  page 77 : 1 = PVDD18_S5_P0 ; 2 = SPI_CPU0_D3
R1530  Q_RES  1K 1% EMPTY  pkg 0402LF  page 77 : 1 = PVDD18_S5_P0 ; 2 = SPI_CPU0_D2
R1531  Q_RES  1K 1% EMPTY  pkg 0402LF  page 77 : 1 = PVDD18_S5_P0 ; 2 = SPI_CPU0_D1
R1532  Q_RES  1K 1% EMPTY  pkg 0402LF  page 77 : 1 = PVDD18_S5_P0 ; 2 = SPI_CPU0_D0
R1533  Q_RES  0 5% CHIP  pkg 0402LF  page 27 : 1 = CPU0_THERMTRIP_R_N ; 2 = CPU1_THERMTRIP_R_N
R1546  Q_RES  1K 1% CHIP  pkg 0402LF  page 151 : 1 = P3V3_AUX ; 2 = RST_MB_STBY_N
R1547  Q_RES  4.7K 5% CHIP  pkg 0402LF  page 77 : 1 = P3V3_AUX ; 2 = SPI_CPU0_LVC3_TPM_CS_N
R1549  Q_RES  33 5% CHIP  pkg 0402LF  page 81 : 1 = ESPI_CPU0_R1_D0 ; 2 = ESPI_CPU0_D0
R1550  Q_RES  33 5% CHIP  pkg 0402LF  page 81 : 1 = ESPI_CPU0_R1_D1 ; 2 = ESPI_CPU0_D1
R1551  Q_RES  33 5% CHIP  pkg 0402LF  page 81 : 1 = ESPI_CPU0_R1_D2 ; 2 = ESPI_CPU0_D2
R1552  Q_RES  33 5% CHIP  pkg 0402LF  page 81 : 1 = ESPI_CPU0_R1_D3 ; 2 = ESPI_CPU0_D3
R1553  Q_RES  33 5% CHIP  pkg 0402LF  page 81 : 1 = ESPI_CPU0_CS1_R_N ; 2 = ESPI_CPU0_CS1_N
R1556  Q_RES  33 5% CHIP  pkg 0402LF  page 81 : 1 = CLK_ESPI_CPU0_R1_CLK1 ; 2 = CLK_ESPI_CPU0_CLK1
R1557  Q_RES  33 5% CHIP  pkg 0402LF  page 81 : 1 = ESPI_CPU0_ALERT_R_N ; 2 = ESPI_CPU0_ALERT_PLD_N
R1558  Q_RES  33 5% CHIP  pkg 0402LF  page 81 : 1 = RST_ESPI_CPU0_RSTOUT_R_N ; 2 = RST_ESPI_CPU0_RSTOUT_N
R1563  Q_RES  33 5% CHIP  pkg 0402LF  page 81 : 1 = UART_LS_EN ; 2 = FM_UART_LS_EN
R1564  Q_RES  33 5% CHIP  pkg 0402LF  page 81 : 1 = FM_ROM_LS_EN ; 2 = ROM_LS_EN
R1567  Q_RES  4.7K 5% CHIP  pkg 0402LF  page 77 : 1 = PVDD18_S5_P0 ; 2 = ROM_LS_EN
R1568  Q_RES  49.9 1% CHIP  pkg 0402LF  page 86 : 1 = I3C_SPD_DDRAF_CPU0_SCL ; 2 = I3C_SPD_DDRA_CPU0_SCL
R1569  Q_RES  49.9 1% CHIP  pkg 0402LF  page 87 : 1 = I3C_SPD_DDRAF_CPU0_SCL ; 2 = I3C_SPD_DDRB_CPU0_SCL
R1570  Q_RES  49.9 1% CHIP  pkg 0402LF  page 88 : 1 = I3C_SPD_DDRAF_CPU0_SCL ; 2 = I3C_SPD_DDRC_CPU0_SCL
R1571  Q_RES  0 5% CHIP  pkg 0402LF  page 190 : 1 = PWRGD_P5V_AUX ; 2 = P3V3_AUX_EN
R1572  Q_RES  49.9 1% CHIP  pkg 0402LF  page 90 : 1 = I3C_SPD_DDRAF_CPU0_SCL ; 2 = I3C_SPD_DDRE_CPU0_SCL
R1573  Q_RES  49.9 1% CHIP  pkg 0402LF  page 91 : 1 = I3C_SPD_DDRAF_CPU0_SCL ; 2 = I3C_SPD_DDRF_CPU0_SCL
R1574  Q_RES  49.9 1% CHIP  pkg 0402LF  page 92 : 1 = I3C_SPD_DDRGL_CPU0_SCL ; 2 = I3C_SPD_DDRG_CPU0_SCL
R1575  Q_RES  49.9 1% CHIP  pkg 0402LF  page 93 : 1 = I3C_SPD_DDRGL_CPU0_SCL ; 2 = I3C_SPD_DDRH_CPU0_SCL
R1576  Q_RES  49.9 1% CHIP  pkg 0402LF  page 94 : 1 = I3C_SPD_DDRGL_CPU0_SCL ; 2 = I3C_SPD_DDRI_CPU0_SCL
R1577  Q_RES  49.9 1% CHIP  pkg 0402LF  page 95 : 1 = I3C_SPD_DDRGL_CPU0_SCL ; 2 = I3C_SPD_DDRJ_CPU0_SCL
R1578  Q_RES  49.9 1% CHIP  pkg 0402LF  page 96 : 1 = I3C_SPD_DDRGL_CPU0_SCL ; 2 = I3C_SPD_DDRK_CPU0_SCL
R1579  Q_RES  49.9 1% CHIP  pkg 0402LF  page 97 : 1 = I3C_SPD_DDRGL_CPU0_SCL ; 2 = I3C_SPD_DDRL_CPU0_SCL
R1580  Q_RES  49.9 1% CHIP  pkg 0402LF  page 98 : 1 = I3C_SPD_DDRAF_CPU1_SCL ; 2 = I3C_SPD_DDRA_CPU1_SCL
R1581  Q_RES  49.9 1% CHIP  pkg 0402LF  page 99 : 1 = I3C_SPD_DDRAF_CPU1_SCL ; 2 = I3C_SPD_DDRB_CPU1_SCL
R1582  Q_RES  49.9 1% CHIP  pkg 0402LF  page 100 : 1 = I3C_SPD_DDRAF_CPU1_SCL ; 2 = I3C_SPD_DDRC_CPU1_SCL
R1583  Q_RES  49.9 1% CHIP  pkg 0402LF  page 101 : 1 = I3C_SPD_DDRAF_CPU1_SCL ; 2 = I3C_SPD_DDRD_CPU1_SCL
R1584  Q_RES  49.9 1% CHIP  pkg 0402LF  page 102 : 1 = I3C_SPD_DDRAF_CPU1_SCL ; 2 = I3C_SPD_DDRE_CPU1_SCL
R1585  Q_RES  49.9 1% CHIP  pkg 0402LF  page 103 : 1 = I3C_SPD_DDRAF_CPU1_SCL ; 2 = I3C_SPD_DDRF_CPU1_SCL
R1586  Q_RES  49.9 1% CHIP  pkg 0402LF  page 104 : 1 = I3C_SPD_DDRGL_CPU1_SCL ; 2 = I3C_SPD_DDRG_CPU1_SCL
R1587  Q_RES  49.9 1% CHIP  pkg 0402LF  page 105 : 1 = I3C_SPD_DDRGL_CPU1_SCL ; 2 = I3C_SPD_DDRH_CPU1_SCL
R1588  Q_RES  49.9 1% CHIP  pkg 0402LF  page 106 : 1 = I3C_SPD_DDRGL_CPU1_SCL ; 2 = I3C_SPD_DDRI_CPU1_SCL
R1589  Q_RES  49.9 1% CHIP  pkg 0402LF  page 107 : 1 = I3C_SPD_DDRGL_CPU1_SCL ; 2 = I3C_SPD_DDRJ_CPU1_SCL
R1590  Q_RES  49.9 1% CHIP  pkg 0402LF  page 108 : 1 = I3C_SPD_DDRGL_CPU1_SCL ; 2 = I3C_SPD_DDRK_CPU1_SCL
R1591  Q_RES  49.9 1% CHIP  pkg 0402LF  page 109 : 1 = I3C_SPD_DDRGL_CPU1_SCL ; 2 = I3C_SPD_DDRL_CPU1_SCL
R1592  Q_RES  33 5% CHIP  pkg 0402LF  page 29 : 1 = ESPI_CPU0_CS1_N ; 2 = CPU0_ESPI_CS0_N
R1593  Q_RES  33 5% CHIP  pkg 0402LF  page 29 : 1 = ESPI_CPU0_ALERT_P0_N ; 2 = CPU0_ESPI0_ALERT_N
R1594  Q_RES  33.2 1% CHIP  pkg 0402LF  page 133 : 1 = OCP_SFF_WAKE_BUFF_N ; 2 = OCP_SFF_WAKE_BUFF_R_N
R1595  Q_RES  33.2 1% CHIP  pkg 0402LF  page 133 : 1 = OCP_SFF_PWRBRK_BUFF_N ; 2 = OCP_SFF_PWRBRK_N
R1605  Q_RES  1K 1% CHIP  pkg 0402LF  page 144 : 1 = PD_M2_0_DEVSLP ; 2 = GND
R1616  Q_RES  33 5% CHIP  pkg 0402LF  page 81 : 1 = FM_ROM_SD_LS_OE ; 2 = ROM_SD_LS_OE
R1619  Q_RES  0 5% CHIP  pkg 0402LF  page 172 : 1 = JTAG_BMC_OE ; 2 = JTAG_BMC_R_D_OE
R1620  Q_RES  33 5% CHIP  pkg 0402LF  page 172 : 1 = HDT_HDR_TRST_N ; 2 = HDT_HDR_TRST_N_R
R1621  Q_RES  1K 1% CHIP  pkg 0402LF  page 172 : 1 = PVDD18_S5_P0 ; 2 = HDT_HDR_TRST_N_R
R1622  Q_RES  4.7K 5% CHIP  pkg 0402LF  page 172 : 1 = P3V3_AUX ; 2 = JTAG_BMC_OE_N
R1624  Q_RES  1K 1% CHIP  pkg 0402LF  page 172 : 1 = PVDD18_S5_P0 ; 2 = HDT_HDR_TCK
R1625  Q_RES  0 5% CHIP  pkg 0402LF  page 172 : 1 = JTAG_TDI_R ; 2 = JTAG_TDI
R1626  Q_RES  1K 1% CHIP  pkg 0402LF  page 172 : 1 = PVDD18_S5_P0 ; 2 = HDT_HDR_TMS
R1627  Q_RES  1K 1% CHIP  pkg 0402LF  page 172 : 1 = PVDD18_S5_P0 ; 2 = HDT_HDR_TDI
R1628  Q_RES  1K 1% CHIP  pkg 0402LF  page 172 : 1 = PVDD18_S5_P0 ; 2 = HDT_HDR_TDO
R1629  Q_RES  1K 1% CHIP  pkg 0402LF  page 172 : 1 = HDT_CPU0_HDT_CONN_TESTEN ; 2 = GND
R1630  Q_RES  1K 1% CHIP  pkg 0402LF  page 172 : 1 = PVDD18_S5_P0 ; 2 = HDT_HDR_DBREQ_R_N
R1631  Q_RES  33 5% CHIP  pkg 0402LF  page 172 : 1 = HDT_HDR_DBREQ_R_N ; 2 = HDT_HDR_DBREQ_N
R1632  Q_RES  33 5% CHIP  pkg 0402LF  page 172 : 1 = HDT_CPU0_HDT_CONN_TESTEN ; 2 = CPU0_HDT_CONN_TESTEN
R1633  Q_RES  0 5% CHIP  pkg 0402LF  page 172 : 1 = JTAG_TCK_R ; 2 = JTAG_TCK
R1634  Q_RES  0 5% CHIP  pkg 0402LF  page 172 : 1 = JTAG_TMS_R ; 2 = JTAG_TMS
R1635  Q_RES  22 1% CHIP  pkg 0402LF  page 172 : 1 = JTAG_TRST_R_N ; 2 = JTAG_TRST_N
R1636  Q_RES  22 1% CHIP  pkg 0402LF  page 172 : 1 = JTAG_DBREQ_R_N ; 2 = JTAG_DBREQ_N
R1637  Q_RES  4.7K 5% CHIP  pkg 0402LF  page 173 : 1 = U152_OE_N ; 2 = GND
R1638  Q_RES  22 1% CHIP  pkg 0402LF  page 173 : 1 = JTAG_P0_R_TCK ; 2 = JTAG_CPU0_TCK
R1639  Q_RES  22 1% CHIP  pkg 0402LF  page 173 : 1 = JTAG_P0_R_TMS ; 2 = JTAG_CPU0_TMS
R1640  Q_RES  22 1% CHIP  pkg 0402LF  page 173 : 1 = JTAG_P0_R_TRST_N ; 2 = JTAG_CPU0_TRST_N
R1641  Q_RES  22 1% CHIP  pkg 0402LF  page 173 : 1 = JTAG_P0_R_DBREQ_N ; 2 = JTAG_CPU0_DBREQ_N
R1642  Q_RES  22 1% CHIP  pkg 0402LF  page 173 : 1 = JTAG_P1_R_TCK ; 2 = JTAG_CPU1_TCK
R1643  Q_RES  22 1% CHIP  pkg 0402LF  page 173 : 1 = JTAG_P1_R_TMS ; 2 = JTAG_CPU1_TMS
R1644  Q_RES  22 1% CHIP  pkg 0402LF  page 173 : 1 = JTAG_P1_R_TRST_N ; 2 = JTAG_CPU1_TRST_N
R1645  Q_RES  22 1% CHIP  pkg 0402LF  page 173 : 1 = JTAG_P1_R_DBREQ_N ; 2 = JTAG_CPU1_DBREQ_N
R1646  Q_RES  1K 1% CHIP  pkg 0402LF  page 174 : 1 = PVDD18_S5_P0 ; 2 = CPU0_HDT_BYPASS_SEL
R1647  Q_RES  1K 1% CHIP  pkg 0402LF  page 174 : 1 = PVDD18_S5_P0 ; 2 = FM_PLD_CPU0_PRSNT_HDT_N
R1648  Q_RES  0 5% CHIP  pkg 0402LF  page 174 : 1 = JTAG_CPU0_R_TDI ; 2 = JTAG_CPU0_TDI
R1649  Q_RES  1K 1% CHIP  pkg 0402LF  page 174 : 1 = PVDD18_S5_P0 ; 2 = CPU1_HDT_BYPASS_SEL
R1650  Q_RES  1K 1% CHIP  pkg 0402LF  page 174 : 1 = PVDD18_S5_P0 ; 2 = FM_PLD_CPU1_PRSNT_HDT_N
R1651  Q_RES  0 5% CHIP  pkg 0402LF  page 174 : 1 = JTAG_CPU1_R_TDI ; 2 = JTAG_CPU1_TDI
R1654  Q_RES  1K 1% CHIP  pkg 0402LF  page 188 : 1 = VR_P5V_EN_D_R ; 2 = VR_P5V_EN_D_R1
R1655  Q_RES  1K 1% EMPTY  pkg 0402LF  page 77 : 1 = P3V3_AUX ; 2 = SPI_CPU0_LVC3_SCM_CS1_N
R1658  Q_RES  4.7K 5% CHIP  pkg 0402LF  page 171 : 1 = SCM_JTAG_MUX_S0 ; 2 = GND
R1659  Q_RES  4.7K 5% EMPTY  pkg 0402LF  page 171 : 1 = P3V3_AUX ; 2 = SCM_JTAG_MUX_S0
R1671  Q_RES  0 5% CHIP  pkg 0402LF  page 131 : 1 = OCP_SFF_AUX_PWR_EN ; 2 = OCP_SFF_AUX_PWR_EN_R
R1673  Q_RES  10K 1% CHIP  pkg 0402LF  page 145 : 1 = P3V3_E1S_0 ; 2 = RST_SMB_E1S_0_N
R1674  Q_RES  10 1% CHIP  pkg 0402LF  page 86 : 1 = I3C_SPD_DDRAF_CPU0_SDA ; 2 = I3C_SPD_DDRA_CPU0_SDA
R1675  Q_RES  10 1% CHIP  pkg 0402LF  page 87 : 1 = I3C_SPD_DDRAF_CPU0_SDA ; 2 = I3C_SPD_DDRB_CPU0_SDA
R1676  Q_RES  10 1% CHIP  pkg 0402LF  page 89 : 1 = I3C_SPD_DDRAF_CPU0_SDA ; 2 = I3C_SPD_DDRD_CPU0_SDA
R1677  Q_RES  10 1% CHIP  pkg 0402LF  page 88 : 1 = I3C_SPD_DDRAF_CPU0_SDA ; 2 = I3C_SPD_DDRC_CPU0_SDA
R1678  Q_RES  10 1% CHIP  pkg 0402LF  page 90 : 1 = I3C_SPD_DDRAF_CPU0_SDA ; 2 = I3C_SPD_DDRE_CPU0_SDA
R1679  Q_RES  10 1% CHIP  pkg 0402LF  page 91 : 1 = I3C_SPD_DDRAF_CPU0_SDA ; 2 = I3C_SPD_DDRF_CPU0_SDA
R1680  Q_RES  10 1% CHIP  pkg 0402LF  page 92 : 1 = I3C_SPD_DDRGL_CPU0_SDA ; 2 = I3C_SPD_DDRG_CPU0_SDA
R1681  Q_RES  10 1% CHIP  pkg 0402LF  page 93 : 1 = I3C_SPD_DDRGL_CPU0_SDA ; 2 = I3C_SPD_DDRH_CPU0_SDA
R1683  Q_RES  10 1% CHIP  pkg 0402LF  page 94 : 1 = I3C_SPD_DDRGL_CPU0_SDA ; 2 = I3C_SPD_DDRI_CPU0_SDA
R1684  Q_RES  10 1% CHIP  pkg 0402LF  page 95 : 1 = I3C_SPD_DDRGL_CPU0_SDA ; 2 = I3C_SPD_DDRJ_CPU0_SDA
R1685  Q_RES  10 1% CHIP  pkg 0402LF  page 96 : 1 = I3C_SPD_DDRGL_CPU0_SDA ; 2 = I3C_SPD_DDRK_CPU0_SDA
R1686  Q_RES  10 1% CHIP  pkg 0402LF  page 97 : 1 = I3C_SPD_DDRGL_CPU0_SDA ; 2 = I3C_SPD_DDRL_CPU0_SDA
R1687  Q_RES  10 1% CHIP  pkg 0402LF  page 98 : 1 = I3C_SPD_DDRAF_CPU1_SDA ; 2 = I3C_SPD_DDRA_CPU1_SDA
R1696  Q_RES  10 1% CHIP  pkg 0402LF  page 99 : 1 = I3C_SPD_DDRAF_CPU1_SDA ; 2 = I3C_SPD_DDRB_CPU1_SDA
R1697  Q_RES  10 1% CHIP  pkg 0402LF  page 100 : 1 = I3C_SPD_DDRAF_CPU1_SDA ; 2 = I3C_SPD_DDRC_CPU1_SDA
R1699  Q_RES  10 1% CHIP  pkg 0402LF  page 101 : 1 = I3C_SPD_DDRAF_CPU1_SDA ; 2 = I3C_SPD_DDRD_CPU1_SDA
R1700  Q_RES  200K 1% CHIP  pkg 0402LF  page 148 : 1 = P3V3_AUX ; 2 = SMB_PCIE_M2_0_EN
R1701  Q_RES  10 1% CHIP  pkg 0402LF  page 102 : 1 = I3C_SPD_DDRAF_CPU1_SDA ; 2 = I3C_SPD_DDRE_CPU1_SDA
R1702  Q_RES  4.7K 5% CHIP  pkg 0402LF  page 148 : 1 = P1V8_AUX ; 2 = SMB_M2_P1_1V8AUX_SDA_R
R1703  Q_RES  4.7K 5% CHIP  pkg 0402LF  page 148 : 1 = P1V8_AUX ; 2 = SMB_M2_P1_1V8AUX_SCL_R
R1704  Q_RES  10 1% CHIP  pkg 0402LF  page 103 : 1 = I3C_SPD_DDRAF_CPU1_SDA ; 2 = I3C_SPD_DDRF_CPU1_SDA
R1705  Q_RES  10 1% CHIP  pkg 0402LF  page 104 : 1 = I3C_SPD_DDRGL_CPU1_SDA ; 2 = I3C_SPD_DDRG_CPU1_SDA
R1707  Q_RES  10 1% CHIP  pkg 0402LF  page 105 : 1 = I3C_SPD_DDRGL_CPU1_SDA ; 2 = I3C_SPD_DDRH_CPU1_SDA
R1708  Q_RES  10 1% CHIP  pkg 0402LF  page 106 : 1 = I3C_SPD_DDRGL_CPU1_SDA ; 2 = I3C_SPD_DDRI_CPU1_SDA
R1709  Q_RES  10 1% CHIP  pkg 0402LF  page 107 : 1 = I3C_SPD_DDRGL_CPU1_SDA ; 2 = I3C_SPD_DDRJ_CPU1_SDA
R1710  Q_RES  10 1% CHIP  pkg 0402LF  page 108 : 1 = I3C_SPD_DDRGL_CPU1_SDA ; 2 = I3C_SPD_DDRK_CPU1_SDA
R1711  Q_RES  10 1% CHIP  pkg 0402LF  page 109 : 1 = I3C_SPD_DDRGL_CPU1_SDA ; 2 = I3C_SPD_DDRL_CPU1_SDA
R1714  Q_RES  0 5% CHIP  pkg 0402LF  page 262 : 1 = SMB_SML1_PMBUS_HSC_SDA ; 2 = SMB_SML1_PMBUS_HSC_R_SDA
R1719  Q_RES  33.2 1% CHIP  pkg 0402LF  page 132 : 1 = OCP_SFF_AUX_PWR_EN ; 2 = OCP_SFF_AUX_PWR_EN_R1
R1727  Q_RES  10K 1% EMPTY  pkg 0402LF  page 171 : 1 = P3V3_AUX ; 2 = JTAG_SCM_TDO
R1728  Q_RES  10K 1% EMPTY  pkg 0402LF  page 171 : 1 = P3V3_AUX ; 2 = JTAG_SCM_TDI
R1729  Q_RES  4.7K 5% CHIP  pkg 0402LF  page 171 : 1 = SCM_JTAG_MUX_S1 ; 2 = GND
R1730  Q_RES  4.7K 5% EMPTY  pkg 0402LF  page 171 : 1 = P3V3_AUX ; 2 = SCM_JTAG_MUX_S1
R1731  Q_RES  10K 1% EMPTY  pkg 0402LF  page 171 : 1 = P3V3_AUX ; 2 = JTAG_SCM_TMS
R1734  Q_RES  10K 1% CHIP  pkg 0402LF  page 171 : 1 = P3V3_AUX ; 2 = JTAG_SCM_TCK
R1735  Q_RES  10K 1% EMPTY  pkg 0402LF  page 171 : 1 = JTAG_SCM_TCK ; 2 = GND
R1736  Q_RES  0 5% CHIP  pkg 0402LF  page 171 : 1 = JTAG_SCM_MUX_R_TCK ; 2 = JTAG_SCM_MUX_TCK
R1737  Q_RES  0 5% CHIP  pkg 0402LF  page 171 : 1 = JTAG_SCM_MUX_R_TMS ; 2 = JTAG_SCM_MUX_TMS
